(kicad_pcb
	(version 20260206)
	(generator "pcbnew")
	(generator_version "10.0")
	(general
		(thickness 1.6)
		(legacy_teardrops no)
	)
	(paper "A4")
	(title_block
		(title "03242023_DA0F0TMBIJ0_F0T_Motherboard_J_brd_V01_OCP.brd")
		(comment 1 "Grand Teton / footprints 2687-2693 of 6105")
	)
	(layers
		(0 "F.Cu" signal "TOP")
		(4 "In1.Cu" signal "GND")
		(6 "In2.Cu" signal "IN1")
		(8 "In3.Cu" signal "GND1")
		(10 "In4.Cu" signal "IN2")
		(12 "In5.Cu" signal "GND2")
		(14 "In6.Cu" signal "IN3")
		(16 "In7.Cu" signal "GND3")
		(18 "In8.Cu" signal "VCC")
		(20 "In9.Cu" signal "VCC1")
		(22 "In10.Cu" signal "GND4")
		(24 "In11.Cu" signal "IN4")
		(26 "In12.Cu" signal "GND5")
		(28 "In13.Cu" signal "IN5")
		(30 "In14.Cu" signal "GND6")
		(32 "In15.Cu" signal "IN6")
		(34 "In16.Cu" signal "GND7")
		(2 "B.Cu" signal "BOTTOM")
		(9 "F.Adhes" user "F.Adhesive")
		(11 "B.Adhes" user "B.Adhesive")
		(13 "F.Paste" user "Package Geometry/Pastemask Top")
		(15 "B.Paste" user "Package Geometry/Pastemask Bottom")
		(5 "F.SilkS" user "Ref Des/Silkscreen Top")
		(7 "B.SilkS" user "Ref Des/Silkscreen Bottom")
		(1 "F.Mask" user "Board Geometry/Soldermask Top")
		(3 "B.Mask" user "Board Geometry/Soldermask Bottom")
		(17 "Dwgs.User" user "User.Drawings")
		(19 "Cmts.User" user "User.Comments")
		(21 "Eco1.User" user "User.Eco1")
		(23 "Eco2.User" user "User.Eco2")
		(25 "Edge.Cuts" user "Board Geometry/Outline")
		(27 "Margin" user)
		(31 "F.CrtYd" user "Package Geometry/Place Bound Top")
		(29 "B.CrtYd" user "Package Geometry/Place Bound Bottom")
		(35 "F.Fab" user "Ref Des/Assembly Top")
		(33 "B.Fab" user "Ref Des/Assembly Bottom")
	)
	(footprint ""
		(layer "F.Cu")
		(at 114.30508 -397.874998 90)
		(property "Reference" "R3032"
			(at 0 0 90)
			(layer "F.SilkS")
			(hide yes)
			(effects
				(font
					(size 1.27 1.27)
				)
			)
		)
		(property "Value" ""
			(at 0 0 90)
			(layer "F.Fab")
			(effects
				(font
					(size 1.27 1.27)
				)
			)
		)
		(duplicate_pad_numbers_are_jumpers no)
		(fp_line
			(start 0.7874 -0.4064)
			(end 0.7874 0.4064)
			(stroke
				(width 0.1524)
				(type default)
			)
			(layer "F.SilkS")
		)
		(fp_line
			(start -0.7874 -0.4064)
			(end 0.7874 -0.4064)
			(stroke
				(width 0.1524)
				(type default)
			)
			(layer "F.SilkS")
		)
		(fp_line
			(start 0.7874 0.4064)
			(end -0.7874 0.4064)
			(stroke
				(width 0.1524)
				(type default)
			)
			(layer "F.SilkS")
		)
		(fp_line
			(start -0.7874 0.4064)
			(end -0.7874 -0.4064)
			(stroke
				(width 0.1524)
				(type default)
			)
			(layer "F.SilkS")
		)
		(fp_line
			(start -0.12065 -0.305054)
			(end -0.12065 -0.2794)
			(stroke
				(width 0.1)
				(type default)
			)
			(layer "F.Fab")
		)
		(fp_line
			(start -0.67945 -0.305054)
			(end -0.12065 -0.305054)
			(stroke
				(width 0.1)
				(type default)
			)
			(layer "F.Fab")
		)
		(fp_line
			(start 0.67945 -0.3048)
			(end 0.67945 0.3048)
			(stroke
				(width 0.1)
				(type default)
			)
			(layer "F.Fab")
		)
		(fp_line
			(start 0.12065 -0.3048)
			(end 0.67945 -0.3048)
			(stroke
				(width 0.1)
				(type default)
			)
			(layer "F.Fab")
		)
		(fp_line
			(start 0.12065 -0.2794)
			(end 0.12065 -0.3048)
			(stroke
				(width 0.1)
				(type default)
			)
			(layer "F.Fab")
		)
		(fp_line
			(start -0.12065 -0.2794)
			(end 0.12065 -0.2794)
			(stroke
				(width 0.1)
				(type default)
			)
			(layer "F.Fab")
		)
		(fp_line
			(start 0.120396 0.2794)
			(end -0.12065 0.2794)
			(stroke
				(width 0.1)
				(type default)
			)
			(layer "F.Fab")
		)
		(fp_line
			(start -0.12065 0.2794)
			(end -0.12065 0.3048)
			(stroke
				(width 0.1)
				(type default)
			)
			(layer "F.Fab")
		)
		(fp_line
			(start 0.67945 0.3048)
			(end 0.120396 0.3048)
			(stroke
				(width 0.1)
				(type default)
			)
			(layer "F.Fab")
		)
		(fp_line
			(start 0.120396 0.3048)
			(end 0.120396 0.2794)
			(stroke
				(width 0.1)
				(type default)
			)
			(layer "F.Fab")
		)
		(fp_line
			(start -0.12065 0.3048)
			(end -0.67945 0.3048)
			(stroke
				(width 0.1)
				(type default)
			)
			(layer "F.Fab")
		)
		(fp_line
			(start -0.67945 0.3048)
			(end -0.67945 -0.305054)
			(stroke
				(width 0.1)
				(type default)
			)
			(layer "F.Fab")
		)
		(pad "1" smd circle
			(at -0.40005 0 90)
			(size 0 0)
			(layers "F.Cu" "F.Mask" "F.Paste")
			(net "FM_SMB_2_ALERT_GPU_N")
		)
		(pad "2" smd circle
			(at 0.40005 0 90)
			(size 0 0)
			(layers "F.Cu" "F.Mask" "F.Paste")
			(net "GND")
		)
	)
	(footprint ""
		(layer "F.Cu")
		(at 324.594728 -408.517344 -90)
		(property "Reference" "C915"
			(at 0 0 270)
			(layer "F.SilkS")
			(hide yes)
			(effects
				(font
					(size 1.27 1.27)
				)
			)
		)
		(property "Value" ""
			(at 0 0 270)
			(layer "F.Fab")
			(effects
				(font
					(size 1.27 1.27)
				)
			)
		)
		(duplicate_pad_numbers_are_jumpers no)
		(fp_line
			(start -0.299974 0.150114)
			(end -0.299974 -0.150114)
			(stroke
				(width 0.1)
				(type default)
			)
			(layer "F.Fab")
		)
		(fp_line
			(start 0.299974 0.150114)
			(end -0.299974 0.150114)
			(stroke
				(width 0.1)
				(type default)
			)
			(layer "F.Fab")
		)
		(fp_line
			(start -0.299974 -0.150114)
			(end 0.299974 -0.150114)
			(stroke
				(width 0.1)
				(type default)
			)
			(layer "F.Fab")
		)
		(fp_line
			(start 0.299974 -0.150114)
			(end 0.299974 0.150114)
			(stroke
				(width 0.1)
				(type default)
			)
			(layer "F.Fab")
		)
		(pad "1" smd rect
			(at -0.2667 0 270)
			(size 0.3048 0.381)
			(layers "F.Cu" "F.Mask" "F.Paste")
			(net "P5E_CPU0_PE0_TX_C_DP<9>")
		)
		(pad "2" smd rect
			(at 0.2667 0 270)
			(size 0.3048 0.381)
			(layers "F.Cu" "F.Mask" "F.Paste")
			(net "P5E_CPU0_PE0_TX_DP<9>")
		)
	)
	(footprint ""
		(layer "F.Cu")
		(at 54.242716 -114.99469)
		(property "Reference" "R3710"
			(at 0 0 0)
			(layer "F.SilkS")
			(hide yes)
			(effects
				(font
					(size 1.27 1.27)
				)
			)
		)
		(property "Value" ""
			(at 0 0 0)
			(layer "F.Fab")
			(effects
				(font
					(size 1.27 1.27)
				)
			)
		)
		(duplicate_pad_numbers_are_jumpers no)
		(fp_line
			(start -0.7874 -0.4064)
			(end 0.7874 -0.4064)
			(stroke
				(width 0.1524)
				(type default)
			)
			(layer "F.SilkS")
		)
		(fp_line
			(start -0.7874 0.4064)
			(end -0.7874 -0.4064)
			(stroke
				(width 0.1524)
				(type default)
			)
			(layer "F.SilkS")
		)
		(fp_line
			(start 0.7874 -0.4064)
			(end 0.7874 0.4064)
			(stroke
				(width 0.1524)
				(type default)
			)
			(layer "F.SilkS")
		)
		(fp_line
			(start 0.7874 0.4064)
			(end -0.7874 0.4064)
			(stroke
				(width 0.1524)
				(type default)
			)
			(layer "F.SilkS")
		)
		(fp_line
			(start -0.67945 -0.305054)
			(end -0.12065 -0.305054)
			(stroke
				(width 0.1)
				(type default)
			)
			(layer "F.Fab")
		)
		(fp_line
			(start -0.67945 0.3048)
			(end -0.67945 -0.305054)
			(stroke
				(width 0.1)
				(type default)
			)
			(layer "F.Fab")
		)
		(fp_line
			(start -0.12065 -0.305054)
			(end -0.12065 -0.2794)
			(stroke
				(width 0.1)
				(type default)
			)
			(layer "F.Fab")
		)
		(fp_line
			(start -0.12065 -0.2794)
			(end 0.12065 -0.2794)
			(stroke
				(width 0.1)
				(type default)
			)
			(layer "F.Fab")
		)
		(fp_line
			(start -0.12065 0.2794)
			(end -0.12065 0.3048)
			(stroke
				(width 0.1)
				(type default)
			)
			(layer "F.Fab")
		)
		(fp_line
			(start -0.12065 0.3048)
			(end -0.67945 0.3048)
			(stroke
				(width 0.1)
				(type default)
			)
			(layer "F.Fab")
		)
		(fp_line
			(start 0.120396 0.2794)
			(end -0.12065 0.2794)
			(stroke
				(width 0.1)
				(type default)
			)
			(layer "F.Fab")
		)
		(fp_line
			(start 0.120396 0.3048)
			(end 0.120396 0.2794)
			(stroke
				(width 0.1)
				(type default)
			)
			(layer "F.Fab")
		)
		(fp_line
			(start 0.12065 -0.3048)
			(end 0.67945 -0.3048)
			(stroke
				(width 0.1)
				(type default)
			)
			(layer "F.Fab")
		)
		(fp_line
			(start 0.12065 -0.2794)
			(end 0.12065 -0.3048)
			(stroke
				(width 0.1)
				(type default)
			)
			(layer "F.Fab")
		)
		(fp_line
			(start 0.67945 -0.3048)
			(end 0.67945 0.3048)
			(stroke
				(width 0.1)
				(type default)
			)
			(layer "F.Fab")
		)
		(fp_line
			(start 0.67945 0.3048)
			(end 0.120396 0.3048)
			(stroke
				(width 0.1)
				(type default)
			)
			(layer "F.Fab")
		)
		(pad "1" smd circle
			(at -0.40005 0)
			(size 0 0)
			(layers "F.Cu" "F.Mask" "F.Paste")
			(net "RST_SMB_SWITCH_N")
		)
		(pad "2" smd circle
			(at 0.40005 0)
			(size 0 0)
			(layers "F.Cu" "F.Mask" "F.Paste")
			(net "PU_RST_SMB_PCIE2_N")
		)
	)
	(footprint ""
		(layer "F.Cu")
		(at 316.900052 -68.449952)
		(property "Reference" "H38"
			(at -3.30454 -3.96621 0)
			(unlocked yes)
			(layer "F.SilkS")
			(effects
				(font
					(size 0.7874 0.5842)
					(thickness 0.1524)
				)
				(justify left)
			)
		)
		(property "Value" ""
			(at 0 0 0)
			(layer "F.Fab")
			(effects
				(font
					(size 1.27 1.27)
				)
			)
		)
		(duplicate_pad_numbers_are_jumpers no)
		(fp_circle
			(center 0 0)
			(end 2.3622 0)
			(stroke
				(width 0.1524)
				(type default)
			)
			(fill no)
			(layer "F.SilkS")
		)
		(fp_circle
			(center 0 0)
			(end 2.3622 0)
			(stroke
				(width 0.1524)
				(type default)
			)
			(fill no)
			(layer "B.SilkS")
		)
		(fp_circle
			(center 0 0)
			(end 2.3622 0)
			(stroke
				(width 0.1)
				(type default)
			)
			(fill no)
			(layer "B.Fab")
		)
		(fp_circle
			(center 0 0)
			(end 2.3622 0)
			(stroke
				(width 0.1)
				(type default)
			)
			(fill no)
			(layer "F.Fab")
		)
		(pad "" np_thru_hole circle
			(at 0 0)
			(size 3.0988 3.0988)
			(drill 3.0988)
			(layers "*.Cu" "*.Mask")
			(clearance 0.254)
			(thermal_gap 0.254)
		)
	)
	(footprint ""
		(layer "F.Cu")
		(at 154.23261 -57.436004)
		(property "Reference" "U98"
			(at -1.397 -2.13233 0)
			(unlocked yes)
			(layer "F.SilkS")
			(effects
				(font
					(size 0.7874 0.5842)
					(thickness 0.1524)
				)
				(justify left)
			)
		)
		(property "Value" ""
			(at 0 0 0)
			(layer "F.Fab")
			(effects
				(font
					(size 1.27 1.27)
				)
			)
		)
		(duplicate_pad_numbers_are_jumpers no)
		(fp_line
			(start -1.3208 -1.525016)
			(end -0.508 -1.525016)
			(stroke
				(width 0.1524)
				(type default)
			)
			(layer "F.SilkS")
		)
		(fp_line
			(start -1.3208 1.525016)
			(end -1.3208 -1.525016)
			(stroke
				(width 0.1524)
				(type default)
			)
			(layer "F.SilkS")
		)
		(fp_line
			(start -0.508 -1.525016)
			(end 0 -0.999998)
			(stroke
				(width 0.1524)
				(type default)
			)
			(layer "F.SilkS")
		)
		(fp_line
			(start 0 -0.999998)
			(end 0.508 -1.525016)
			(stroke
				(width 0.1524)
				(type default)
			)
			(layer "F.SilkS")
		)
		(fp_line
			(start 0.508 -1.525016)
			(end 1.3208 -1.525016)
			(stroke
				(width 0.1524)
				(type default)
			)
			(layer "F.SilkS")
		)
		(fp_line
			(start 1.3208 -1.525016)
			(end 1.3208 1.525016)
			(stroke
				(width 0.1524)
				(type default)
			)
			(layer "F.SilkS")
		)
		(fp_line
			(start 1.3208 1.525016)
			(end -1.3208 1.525016)
			(stroke
				(width 0.1524)
				(type default)
			)
			(layer "F.SilkS")
		)
		(fp_poly
			(pts
				(xy -3.937 -0.635) (xy -3.937 -1.397) (xy -3.175 -1.016)
			)
			(stroke
				(width 0)
				(type default)
			)
			(fill yes)
			(layer "F.SilkS")
		)
		(fp_line
			(start -3.037078 -1.20777)
			(end -1.524 -1.20777)
			(stroke
				(width 0.1)
				(type default)
			)
			(layer "F.Fab")
		)
		(fp_line
			(start -3.037078 1.203706)
			(end -3.037078 -1.20777)
			(stroke
				(width 0.1)
				(type default)
			)
			(layer "F.Fab")
		)
		(fp_line
			(start -1.5494 1.203706)
			(end -3.037078 1.203706)
			(stroke
				(width 0.1)
				(type default)
			)
			(layer "F.Fab")
		)
		(fp_line
			(start -1.5494 1.5494)
			(end -1.5494 1.203706)
			(stroke
				(width 0.1)
				(type default)
			)
			(layer "F.Fab")
		)
		(fp_line
			(start -1.524 -1.524)
			(end 1.524 -1.524)
			(stroke
				(width 0.1)
				(type default)
			)
			(layer "F.Fab")
		)
		(fp_line
			(start -1.524 -1.20777)
			(end -1.524 -1.524)
			(stroke
				(width 0.1)
				(type default)
			)
			(layer "F.Fab")
		)
		(fp_line
			(start 1.524 -1.524)
			(end 1.524 -1.20777)
			(stroke
				(width 0.1)
				(type default)
			)
			(layer "F.Fab")
		)
		(fp_line
			(start 1.524 -1.20777)
			(end 3.0353 -1.20777)
			(stroke
				(width 0.1)
				(type default)
			)
			(layer "F.Fab")
		)
		(fp_line
			(start 1.524 1.208786)
			(end 1.524 1.5494)
			(stroke
				(width 0.1)
				(type default)
			)
			(layer "F.Fab")
		)
		(fp_line
			(start 1.524 1.5494)
			(end -1.5494 1.5494)
			(stroke
				(width 0.1)
				(type default)
			)
			(layer "F.Fab")
		)
		(fp_line
			(start 3.0353 -1.20777)
			(end 3.0353 1.208786)
			(stroke
				(width 0.1)
				(type default)
			)
			(layer "F.Fab")
		)
		(fp_line
			(start 3.0353 1.208786)
			(end 1.524 1.208786)
			(stroke
				(width 0.1)
				(type default)
			)
			(layer "F.Fab")
		)
		(fp_poly
			(pts
				(xy -3.175 -1.016) (xy -3.937 -0.635) (xy -3.937 -1.397)
			)
			(stroke
				(width 0)
				(type default)
			)
			(fill yes)
			(layer "F.Fab")
		)
		(pad "1" smd rect
			(at -2.234946 -0.975106 270)
			(size 0.3556 1.4986)
			(layers "F.Cu" "F.Mask" "F.Paste")
			(net "GND")
		)
		(pad "2" smd rect
			(at -2.234946 -0.32512 270)
			(size 0.3556 1.4986)
			(layers "F.Cu" "F.Mask" "F.Paste")
			(net "P1V8_PCH_AUX")
		)
		(pad "3" smd rect
			(at -2.234946 0.32512 270)
			(size 0.3556 1.4986)
			(layers "F.Cu" "F.Mask" "F.Paste")
			(net "SMB_M2_P0_1V8AUX_SCL_R")
		)
		(pad "4" smd rect
			(at -2.234946 0.975106 270)
			(size 0.3556 1.4986)
			(layers "F.Cu" "F.Mask" "F.Paste")
			(net "SMB_M2_P0_1V8AUX_SDA_R")
		)
		(pad "5" smd rect
			(at 2.234946 0.975106 270)
			(size 0.3556 1.4986)
			(layers "F.Cu" "F.Mask" "F.Paste")
			(net "SMB_SENSOR_M2_P0_3V3AUX_SDA")
		)
		(pad "6" smd rect
			(at 2.234946 0.32512 270)
			(size 0.3556 1.4986)
			(layers "F.Cu" "F.Mask" "F.Paste")
			(net "SMB_SENSOR_M2_P0_3V3AUX_SCL")
		)
		(pad "7" smd rect
			(at 2.234946 -0.32512 270)
			(size 0.3556 1.4986)
			(layers "F.Cu" "F.Mask" "F.Paste")
			(net "SMB_PCIE_M2_0_EN")
		)
		(pad "8" smd rect
			(at 2.234946 -0.975106 270)
			(size 0.3556 1.4986)
			(layers "F.Cu" "F.Mask" "F.Paste")
			(net "SMB_PCIE_M2_0_EN")
		)
	)
	(footprint ""
		(layer "F.Cu")
		(at 104.349804 -244.032024 90)
		(property "Reference" "C252"
			(at 0 0 90)
			(layer "F.SilkS")
			(hide yes)
			(effects
				(font
					(size 1.27 1.27)
				)
			)
		)
		(property "Value" ""
			(at 0 0 90)
			(layer "F.Fab")
			(effects
				(font
					(size 1.27 1.27)
				)
			)
		)
		(duplicate_pad_numbers_are_jumpers no)
		(fp_line
			(start 0.7874 -0.4064)
			(end 0.7874 0.4064)
			(stroke
				(width 0.1524)
				(type default)
			)
			(layer "F.SilkS")
		)
		(fp_line
			(start -0.7874 -0.4064)
			(end 0.7874 -0.4064)
			(stroke
				(width 0.1524)
				(type default)
			)
			(layer "F.SilkS")
		)
		(fp_line
			(start 0.7874 0.4064)
			(end -0.7874 0.4064)
			(stroke
				(width 0.1524)
				(type default)
			)
			(layer "F.SilkS")
		)
		(fp_line
			(start -0.7874 0.4064)
			(end -0.7874 -0.4064)
			(stroke
				(width 0.1524)
				(type default)
			)
			(layer "F.SilkS")
		)
		(fp_line
			(start -0.12065 -0.305054)
			(end -0.12065 -0.2794)
			(stroke
				(width 0.1)
				(type default)
			)
			(layer "F.Fab")
		)
		(fp_line
			(start -0.67945 -0.305054)
			(end -0.12065 -0.305054)
			(stroke
				(width 0.1)
				(type default)
			)
			(layer "F.Fab")
		)
		(fp_line
			(start 0.67945 -0.3048)
			(end 0.67945 0.3048)
			(stroke
				(width 0.1)
				(type default)
			)
			(layer "F.Fab")
		)
		(fp_line
			(start 0.12065 -0.3048)
			(end 0.67945 -0.3048)
			(stroke
				(width 0.1)
				(type default)
			)
			(layer "F.Fab")
		)
		(fp_line
			(start 0.12065 -0.2794)
			(end 0.12065 -0.3048)
			(stroke
				(width 0.1)
				(type default)
			)
			(layer "F.Fab")
		)
		(fp_line
			(start -0.12065 -0.2794)
			(end 0.12065 -0.2794)
			(stroke
				(width 0.1)
				(type default)
			)
			(layer "F.Fab")
		)
		(fp_line
			(start 0.120396 0.2794)
			(end -0.12065 0.2794)
			(stroke
				(width 0.1)
				(type default)
			)
			(layer "F.Fab")
		)
		(fp_line
			(start -0.12065 0.2794)
			(end -0.12065 0.3048)
			(stroke
				(width 0.1)
				(type default)
			)
			(layer "F.Fab")
		)
		(fp_line
			(start 0.67945 0.3048)
			(end 0.120396 0.3048)
			(stroke
				(width 0.1)
				(type default)
			)
			(layer "F.Fab")
		)
		(fp_line
			(start 0.120396 0.3048)
			(end 0.120396 0.2794)
			(stroke
				(width 0.1)
				(type default)
			)
			(layer "F.Fab")
		)
		(fp_line
			(start -0.12065 0.3048)
			(end -0.67945 0.3048)
			(stroke
				(width 0.1)
				(type default)
			)
			(layer "F.Fab")
		)
		(fp_line
			(start -0.67945 0.3048)
			(end -0.67945 -0.305054)
			(stroke
				(width 0.1)
				(type default)
			)
			(layer "F.Fab")
		)
		(pad "1" smd circle
			(at -0.40005 0 90)
			(size 0 0)
			(layers "F.Cu" "F.Mask" "F.Paste")
			(net "PVCCIN_CPU1")
		)
		(pad "2" smd circle
			(at 0.40005 0 90)
			(size 0 0)
			(layers "F.Cu" "F.Mask" "F.Paste")
			(net "GND")
		)
	)
	(footprint ""
		(layer "F.Cu")
		(at 432.67884 -184.544208)
		(property "Reference" "PR3339"
			(at 0 0 0)
			(layer "F.SilkS")
			(hide yes)
			(effects
				(font
					(size 1.27 1.27)
				)
			)
		)
		(property "Value" ""
			(at 0 0 0)
			(layer "F.Fab")
			(effects
				(font
					(size 1.27 1.27)
				)
			)
		)
		(duplicate_pad_numbers_are_jumpers no)
		(fp_line
			(start -0.7874 -0.4064)
			(end 0.7874 -0.4064)
			(stroke
				(width 0.1524)
				(type default)
			)
			(layer "F.SilkS")
		)
		(fp_line
			(start -0.7874 0.4064)
			(end -0.7874 -0.4064)
			(stroke
				(width 0.1524)
				(type default)
			)
			(layer "F.SilkS")
		)
		(fp_line
			(start 0.7874 -0.4064)
			(end 0.7874 0.4064)
			(stroke
				(width 0.1524)
				(type default)
			)
			(layer "F.SilkS")
		)
		(fp_line
			(start 0.7874 0.4064)
			(end -0.7874 0.4064)
			(stroke
				(width 0.1524)
				(type default)
			)
			(layer "F.SilkS")
		)
		(fp_line
			(start -0.67945 -0.305054)
			(end -0.12065 -0.305054)
			(stroke
				(width 0.1)
				(type default)
			)
			(layer "F.Fab")
		)
		(fp_line
			(start -0.67945 0.3048)
			(end -0.67945 -0.305054)
			(stroke
				(width 0.1)
				(type default)
			)
			(layer "F.Fab")
		)
		(fp_line
			(start -0.12065 -0.305054)
			(end -0.12065 -0.2794)
			(stroke
				(width 0.1)
				(type default)
			)
			(layer "F.Fab")
		)
		(fp_line
			(start -0.12065 -0.2794)
			(end 0.12065 -0.2794)
			(stroke
				(width 0.1)
				(type default)
			)
			(layer "F.Fab")
		)
		(fp_line
			(start -0.12065 0.2794)
			(end -0.12065 0.3048)
			(stroke
				(width 0.1)
				(type default)
			)
			(layer "F.Fab")
		)
		(fp_line
			(start -0.12065 0.3048)
			(end -0.67945 0.3048)
			(stroke
				(width 0.1)
				(type default)
			)
			(layer "F.Fab")
		)
		(fp_line
			(start 0.120396 0.2794)
			(end -0.12065 0.2794)
			(stroke
				(width 0.1)
				(type default)
			)
			(layer "F.Fab")
		)
		(fp_line
			(start 0.120396 0.3048)
			(end 0.120396 0.2794)
			(stroke
				(width 0.1)
				(type default)
			)
			(layer "F.Fab")
		)
		(fp_line
			(start 0.12065 -0.3048)
			(end 0.67945 -0.3048)
			(stroke
				(width 0.1)
				(type default)
			)
			(layer "F.Fab")
		)
		(fp_line
			(start 0.12065 -0.2794)
			(end 0.12065 -0.3048)
			(stroke
				(width 0.1)
				(type default)
			)
			(layer "F.Fab")
		)
		(fp_line
			(start 0.67945 -0.3048)
			(end 0.67945 0.3048)
			(stroke
				(width 0.1)
				(type default)
			)
			(layer "F.Fab")
		)
		(fp_line
			(start 0.67945 0.3048)
			(end 0.120396 0.3048)
			(stroke
				(width 0.1)
				(type default)
			)
			(layer "F.Fab")
		)
		(pad "1" smd circle
			(at -0.40005 0)
			(size 0 0)
			(layers "F.Cu" "F.Mask" "F.Paste")
			(net "P3V3_AUX")
		)
		(pad "2" smd circle
			(at 0.40005 0)
			(size 0 0)
			(layers "F.Cu" "F.Mask" "F.Paste")
			(net "PVNN_MAIN_CPU0_VCC")
		)
	)
)
